# T6G (Grand Teton) — schematic netlist excerpt (pin names and nets, part order shuffled) for the footprints in the layout excerpt that follows; sources: Cadence DE-HDL packaged netlist, KiCad conversion of 04192023_DAF0TMB3IC0_F0TG_MB_C_brd_V02_OCP.brd

PC193  Q_CAP  0.1UF 25V 10% X7R  pkg 0402  page 207 : A = PVDD11_S3_P0_VMON ; B = GND
R1824  Q_RES  10K 1% CHIP  pkg 0402LF  page 133 : A = P3V3_OCP_SFF ; B = IRQ_LVC3_OCP_SFF_WAKE_N

(kicad_pcb
	(version 20260206)
	(generator "pcbnew")
	(generator_version "10.0")
	(general
		(thickness 1.6)
		(legacy_teardrops no)
	)
	(paper "A4")
	(title_block
		(title "04192023_DAF0TMB3IC0_F0TG_MB_C_brd_V02_OCP.brd")
		(comment 1 "Grand Teton / footprints 4007-4008 of 8354")
	)
	(layers
		(0 "F.Cu" signal "TOP")
		(4 "In1.Cu" signal "GND")
		(6 "In2.Cu" signal "IN1")
		(8 "In3.Cu" signal "GND1")
		(10 "In4.Cu" signal "IN2")
		(12 "In5.Cu" signal "GND2")
		(14 "In6.Cu" signal "IN3")
		(16 "In7.Cu" signal "GND3")
		(18 "In8.Cu" signal "VCC")
		(20 "In9.Cu" signal "VCC1")
		(22 "In10.Cu" signal "GND4")
		(24 "In11.Cu" signal "IN4")
		(26 "In12.Cu" signal "GND5")
		(28 "In13.Cu" signal "IN5")
		(30 "In14.Cu" signal "GND6")
		(32 "In15.Cu" signal "IN6")
		(34 "In16.Cu" signal "GND7")
		(2 "B.Cu" signal "BOTTOM")
		(9 "F.Adhes" user "F.Adhesive")
		(11 "B.Adhes" user "B.Adhesive")
		(13 "F.Paste" user "Package Geometry/Pastemask Top")
		(15 "B.Paste" user "Package Geometry/Pastemask Bottom")
		(5 "F.SilkS" user "Ref Des/Silkscreen Top")
		(7 "B.SilkS" user "Ref Des/Silkscreen Bottom")
		(1 "F.Mask" user "Board Geometry/Soldermask Top")
		(3 "B.Mask" user "Board Geometry/Soldermask Bottom")
		(17 "Dwgs.User" user "User.Drawings")
		(19 "Cmts.User" user "User.Comments")
		(21 "Eco1.User" user "User.Eco1")
		(23 "Eco2.User" user "User.Eco2")
		(25 "Edge.Cuts" user "Board Geometry/Outline")
		(27 "Margin" user)
		(31 "F.CrtYd" user "Package Geometry/Place Bound Top")
		(29 "B.CrtYd" user "Package Geometry/Place Bound Bottom")
		(35 "F.Fab" user "Ref Des/Assembly Top")
		(33 "B.Fab" user "Ref Des/Assembly Bottom")
	)
	(footprint ""
		(layer "F.Cu")
		(at 455.01306 -37.295836)
		(property "Reference" "R1824"
			(at 0 0 0)
			(layer "F.SilkS")
			(hide yes)
			(effects
				(font
					(size 1.27 1.27)
				)
			)
		)
		(property "Value" ""
			(at 0 0 0)
			(layer "F.Fab")
			(effects
				(font
					(size 1.27 1.27)
				)
			)
		)
		(duplicate_pad_numbers_are_jumpers no)
		(fp_line
			(start -0.7874 -0.4064)
			(end 0.7874 -0.4064)
			(stroke
				(width 0.1524)
				(type default)
			)
			(layer "F.SilkS")
		)
		(fp_line
			(start -0.7874 0.4064)
			(end -0.7874 -0.4064)
			(stroke
				(width 0.1524)
				(type default)
			)
			(layer "F.SilkS")
		)
		(fp_line
			(start 0.7874 -0.4064)
			(end 0.7874 0.4064)
			(stroke
				(width 0.1524)
				(type default)
			)
			(layer "F.SilkS")
		)
		(fp_line
			(start 0.7874 0.4064)
			(end -0.7874 0.4064)
			(stroke
				(width 0.1524)
				(type default)
			)
			(layer "F.SilkS")
		)
		(fp_line
			(start -0.67945 -0.305054)
			(end -0.12065 -0.305054)
			(stroke
				(width 0.1)
				(type default)
			)
			(layer "F.Fab")
		)
		(fp_line
			(start -0.67945 0.3048)
			(end -0.67945 -0.305054)
			(stroke
				(width 0.1)
				(type default)
			)
			(layer "F.Fab")
		)
		(fp_line
			(start -0.12065 -0.305054)
			(end -0.12065 -0.2794)
			(stroke
				(width 0.1)
				(type default)
			)
			(layer "F.Fab")
		)
		(fp_line
			(start -0.12065 -0.2794)
			(end 0.12065 -0.2794)
			(stroke
				(width 0.1)
				(type default)
			)
			(layer "F.Fab")
		)
		(fp_line
			(start -0.12065 0.2794)
			(end -0.12065 0.3048)
			(stroke
				(width 0.1)
				(type default)
			)
			(layer "F.Fab")
		)
		(fp_line
			(start -0.12065 0.3048)
			(end -0.67945 0.3048)
			(stroke
				(width 0.1)
				(type default)
			)
			(layer "F.Fab")
		)
		(fp_line
			(start 0.120396 0.2794)
			(end -0.12065 0.2794)
			(stroke
				(width 0.1)
				(type default)
			)
			(layer "F.Fab")
		)
		(fp_line
			(start 0.120396 0.3048)
			(end 0.120396 0.2794)
			(stroke
				(width 0.1)
				(type default)
			)
			(layer "F.Fab")
		)
		(fp_line
			(start 0.12065 -0.3048)
			(end 0.67945 -0.3048)
			(stroke
				(width 0.1)
				(type default)
			)
			(layer "F.Fab")
		)
		(fp_line
			(start 0.12065 -0.2794)
			(end 0.12065 -0.3048)
			(stroke
				(width 0.1)
				(type default)
			)
			(layer "F.Fab")
		)
		(fp_line
			(start 0.67945 -0.3048)
			(end 0.67945 0.3048)
			(stroke
				(width 0.1)
				(type default)
			)
			(layer "F.Fab")
		)
		(fp_line
			(start 0.67945 0.3048)
			(end 0.120396 0.3048)
			(stroke
				(width 0.1)
				(type default)
			)
			(layer "F.Fab")
		)
		(pad "1" smd circle
			(at -0.40005 0)
			(size 0 0)
			(layers "F.Cu" "F.Mask" "F.Paste")
			(net "P3V3_OCP_SFF")
		)
		(pad "2" smd circle
			(at 0.40005 0)
			(size 0 0)
			(layers "F.Cu" "F.Mask" "F.Paste")
			(net "IRQ_LVC3_OCP_SFF_WAKE_N")
		)
	)
	(footprint ""
		(layer "F.Cu")
		(at 423.61866 -362.79963)
		(property "Reference" "PC193"
			(at 0 0 0)
			(layer "F.SilkS")
			(hide yes)
			(effects
				(font
					(size 1.27 1.27)
				)
			)
		)
		(property "Value" ""
			(at 0 0 0)
			(layer "F.Fab")
			(effects
				(font
					(size 1.27 1.27)
				)
			)
		)
		(duplicate_pad_numbers_are_jumpers no)
		(fp_line
			(start -0.7874 -0.4064)
			(end 0.7874 -0.4064)
			(stroke
				(width 0.1524)
				(type default)
			)
			(layer "F.SilkS")
		)
		(fp_line
			(start -0.7874 0.4064)
			(end -0.7874 -0.4064)
			(stroke
				(width 0.1524)
				(type default)
			)
			(layer "F.SilkS")
		)
		(fp_line
			(start 0.7874 -0.4064)
			(end 0.7874 0.4064)
			(stroke
				(width 0.1524)
				(type default)
			)
			(layer "F.SilkS")
		)
		(fp_line
			(start 0.7874 0.4064)
			(end -0.7874 0.4064)
			(stroke
				(width 0.1524)
				(type default)
			)
			(layer "F.SilkS")
		)
		(fp_line
			(start -0.67945 -0.305054)
			(end -0.12065 -0.305054)
			(stroke
				(width 0.1)
				(type default)
			)
			(layer "F.Fab")
		)
		(fp_line
			(start -0.67945 0.3048)
			(end -0.67945 -0.305054)
			(stroke
				(width 0.1)
				(type default)
			)
			(layer "F.Fab")
		)
		(fp_line
			(start -0.12065 -0.305054)
			(end -0.12065 -0.2794)
			(stroke
				(width 0.1)
				(type default)
			)
			(layer "F.Fab")
		)
		(fp_line
			(start -0.12065 -0.2794)
			(end 0.12065 -0.2794)
			(stroke
				(width 0.1)
				(type default)
			)
			(layer "F.Fab")
		)
		(fp_line
			(start -0.12065 0.2794)
			(end -0.12065 0.3048)
			(stroke
				(width 0.1)
				(type default)
			)
			(layer "F.Fab")
		)
		(fp_line
			(start -0.12065 0.3048)
			(end -0.67945 0.3048)
			(stroke
				(width 0.1)
				(type default)
			)
			(layer "F.Fab")
		)
		(fp_line
			(start 0.120396 0.2794)
			(end -0.12065 0.2794)
			(stroke
				(width 0.1)
				(type default)
			)
			(layer "F.Fab")
		)
		(fp_line
			(start 0.120396 0.3048)
			(end 0.120396 0.2794)
			(stroke
				(width 0.1)
				(type default)
			)
			(layer "F.Fab")
		)
		(fp_line
			(start 0.12065 -0.3048)
			(end 0.67945 -0.3048)
			(stroke
				(width 0.1)
				(type default)
			)
			(layer "F.Fab")
		)
		(fp_line
			(start 0.12065 -0.2794)
			(end 0.12065 -0.3048)
			(stroke
				(width 0.1)
				(type default)
			)
			(layer "F.Fab")
		)
		(fp_line
			(start 0.67945 -0.3048)
			(end 0.67945 0.3048)
			(stroke
				(width 0.1)
				(type default)
			)
			(layer "F.Fab")
		)
		(fp_line
			(start 0.67945 0.3048)
			(end 0.120396 0.3048)
			(stroke
				(width 0.1)
				(type default)
			)
			(layer "F.Fab")
		)
		(pad "1" smd circle
			(at -0.40005 0)
			(size 0 0)
			(layers "F.Cu" "F.Mask" "F.Paste")
			(net "PVDD11_S3_P0_VMON")
		)
		(pad "2" smd circle
			(at 0.40005 0)
			(size 0 0)
			(layers "F.Cu" "F.Mask" "F.Paste")
			(net "GND")
		)
	)
)
